# T6G (Grand Teton) — schematic netlist excerpt (pin names and nets, part order shuffled) for the footprints in the layout excerpt that follows; sources: Cadence DE-HDL packaged netlist, KiCad conversion of 04192023_DAF0TMB3IC0_F0TG_MB_C_brd_V02_OCP.brd

R1516  Q_RES  33.2 1% CHIP  pkg 0402LF  page 151 : A = SMB_HOST_CLK_3V3AUX_SCL ; B = SMB_HOST_CLK_3V3AUX_SCL_R1
R6123  Q_RES  1K 1% EMPTY  pkg 0402LF  page 84 : A = PVDD18_S5_P0 ; B = FM_BOARD_SKU_ID1

(kicad_pcb
	(version 20260206)
	(generator "pcbnew")
	(generator_version "10.0")
	(general
		(thickness 1.6)
		(legacy_teardrops no)
	)
	(paper "A4")
	(title_block
		(title "04192023_DAF0TMB3IC0_F0TG_MB_C_brd_V02_OCP.brd")
		(comment 1 "Grand Teton / footprints 5275-5276 of 8354")
	)
	(layers
		(0 "F.Cu" signal "TOP")
		(4 "In1.Cu" signal "GND")
		(6 "In2.Cu" signal "IN1")
		(8 "In3.Cu" signal "GND1")
		(10 "In4.Cu" signal "IN2")
		(12 "In5.Cu" signal "GND2")
		(14 "In6.Cu" signal "IN3")
		(16 "In7.Cu" signal "GND3")
		(18 "In8.Cu" signal "VCC")
		(20 "In9.Cu" signal "VCC1")
		(22 "In10.Cu" signal "GND4")
		(24 "In11.Cu" signal "IN4")
		(26 "In12.Cu" signal "GND5")
		(28 "In13.Cu" signal "IN5")
		(30 "In14.Cu" signal "GND6")
		(32 "In15.Cu" signal "IN6")
		(34 "In16.Cu" signal "GND7")
		(2 "B.Cu" signal "BOTTOM")
		(9 "F.Adhes" user "F.Adhesive")
		(11 "B.Adhes" user "B.Adhesive")
		(13 "F.Paste" user "Package Geometry/Pastemask Top")
		(15 "B.Paste" user "Package Geometry/Pastemask Bottom")
		(5 "F.SilkS" user "Ref Des/Silkscreen Top")
		(7 "B.SilkS" user "Ref Des/Silkscreen Bottom")
		(1 "F.Mask" user "Board Geometry/Soldermask Top")
		(3 "B.Mask" user "Board Geometry/Soldermask Bottom")
		(17 "Dwgs.User" user "User.Drawings")
		(19 "Cmts.User" user "User.Comments")
		(21 "Eco1.User" user "User.Eco1")
		(23 "Eco2.User" user "User.Eco2")
		(25 "Edge.Cuts" user "Board Geometry/Outline")
		(27 "Margin" user)
		(31 "F.CrtYd" user "Package Geometry/Place Bound Top")
		(29 "B.CrtYd" user "Package Geometry/Place Bound Bottom")
		(35 "F.Fab" user "Ref Des/Assembly Top")
		(33 "B.Fab" user "Ref Des/Assembly Bottom")
	)
	(footprint ""
		(layer "B.Cu")
		(at 101.854 -413.2072 180)
		(property "Reference" "R1516"
			(at 0 0 0)
			(layer "B.SilkS")
			(hide yes)
			(effects
				(font
					(size 1.27 1.27)
				)
				(justify mirror)
			)
		)
		(property "Value" ""
			(at 0 0 0)
			(layer "B.Fab")
			(effects
				(font
					(size 1.27 1.27)
				)
				(justify mirror)
			)
		)
		(duplicate_pad_numbers_are_jumpers no)
		(fp_line
			(start 0.7874 0.4064)
			(end 0.7874 -0.4064)
			(stroke
				(width 0.1524)
				(type default)
			)
			(layer "B.SilkS")
		)
		(fp_line
			(start 0.7874 -0.4064)
			(end -0.7874 -0.4064)
			(stroke
				(width 0.1524)
				(type default)
			)
			(layer "B.SilkS")
		)
		(fp_line
			(start -0.7874 0.4064)
			(end 0.7874 0.4064)
			(stroke
				(width 0.1524)
				(type default)
			)
			(layer "B.SilkS")
		)
		(fp_line
			(start -0.7874 -0.4064)
			(end -0.7874 0.4064)
			(stroke
				(width 0.1524)
				(type default)
			)
			(layer "B.SilkS")
		)
		(fp_line
			(start 0.67945 0.3048)
			(end 0.67945 -0.305054)
			(stroke
				(width 0.1)
				(type default)
			)
			(layer "B.Fab")
		)
		(fp_line
			(start 0.67945 -0.305054)
			(end 0.12065 -0.305054)
			(stroke
				(width 0.1)
				(type default)
			)
			(layer "B.Fab")
		)
		(fp_line
			(start 0.12065 0.3048)
			(end 0.67945 0.3048)
			(stroke
				(width 0.1)
				(type default)
			)
			(layer "B.Fab")
		)
		(fp_line
			(start 0.12065 0.2794)
			(end 0.12065 0.3048)
			(stroke
				(width 0.1)
				(type default)
			)
			(layer "B.Fab")
		)
		(fp_line
			(start 0.12065 -0.2794)
			(end -0.12065 -0.2794)
			(stroke
				(width 0.1)
				(type default)
			)
			(layer "B.Fab")
		)
		(fp_line
			(start 0.12065 -0.305054)
			(end 0.12065 -0.2794)
			(stroke
				(width 0.1)
				(type default)
			)
			(layer "B.Fab")
		)
		(fp_line
			(start -0.120396 0.3048)
			(end -0.120396 0.2794)
			(stroke
				(width 0.1)
				(type default)
			)
			(layer "B.Fab")
		)
		(fp_line
			(start -0.120396 0.2794)
			(end 0.12065 0.2794)
			(stroke
				(width 0.1)
				(type default)
			)
			(layer "B.Fab")
		)
		(fp_line
			(start -0.12065 -0.2794)
			(end -0.12065 -0.3048)
			(stroke
				(width 0.1)
				(type default)
			)
			(layer "B.Fab")
		)
		(fp_line
			(start -0.12065 -0.3048)
			(end -0.67945 -0.3048)
			(stroke
				(width 0.1)
				(type default)
			)
			(layer "B.Fab")
		)
		(fp_line
			(start -0.67945 0.3048)
			(end -0.120396 0.3048)
			(stroke
				(width 0.1)
				(type default)
			)
			(layer "B.Fab")
		)
		(fp_line
			(start -0.67945 -0.3048)
			(end -0.67945 0.3048)
			(stroke
				(width 0.1)
				(type default)
			)
			(layer "B.Fab")
		)
		(pad "1" smd circle
			(at 0.40005 0)
			(size 0 0)
			(layers "B.Cu" "B.Mask" "B.Paste")
			(net "SMB_HOST_CLK_3V3AUX_SCL")
		)
		(pad "2" smd circle
			(at -0.40005 0)
			(size 0 0)
			(layers "B.Cu" "B.Mask" "B.Paste")
			(net "SMB_HOST_CLK_3V3AUX_SCL_R1")
		)
	)
	(footprint ""
		(layer "B.Cu")
		(at 402.844 -349.218504 -90)
		(property "Reference" "R6123"
			(at 0 0 90)
			(layer "B.SilkS")
			(hide yes)
			(effects
				(font
					(size 1.27 1.27)
				)
				(justify mirror)
			)
		)
		(property "Value" ""
			(at 0 0 90)
			(layer "B.Fab")
			(effects
				(font
					(size 1.27 1.27)
				)
				(justify mirror)
			)
		)
		(duplicate_pad_numbers_are_jumpers no)
		(fp_line
			(start -0.7874 0.4064)
			(end 0.7874 0.4064)
			(stroke
				(width 0.1524)
				(type default)
			)
			(layer "B.SilkS")
		)
		(fp_line
			(start 0.7874 0.4064)
			(end 0.7874 -0.4064)
			(stroke
				(width 0.1524)
				(type default)
			)
			(layer "B.SilkS")
		)
		(fp_line
			(start -0.7874 -0.4064)
			(end -0.7874 0.4064)
			(stroke
				(width 0.1524)
				(type default)
			)
			(layer "B.SilkS")
		)
		(fp_line
			(start 0.7874 -0.4064)
			(end -0.7874 -0.4064)
			(stroke
				(width 0.1524)
				(type default)
			)
			(layer "B.SilkS")
		)
		(fp_line
			(start -0.67945 0.3048)
			(end -0.120396 0.3048)
			(stroke
				(width 0.1)
				(type default)
			)
			(layer "B.Fab")
		)
		(fp_line
			(start -0.120396 0.3048)
			(end -0.120396 0.2794)
			(stroke
				(width 0.1)
				(type default)
			)
			(layer "B.Fab")
		)
		(fp_line
			(start 0.12065 0.3048)
			(end 0.67945 0.3048)
			(stroke
				(width 0.1)
				(type default)
			)
			(layer "B.Fab")
		)
		(fp_line
			(start 0.67945 0.3048)
			(end 0.67945 -0.305054)
			(stroke
				(width 0.1)
				(type default)
			)
			(layer "B.Fab")
		)
		(fp_line
			(start -0.120396 0.2794)
			(end 0.12065 0.2794)
			(stroke
				(width 0.1)
				(type default)
			)
			(layer "B.Fab")
		)
		(fp_line
			(start 0.12065 0.2794)
			(end 0.12065 0.3048)
			(stroke
				(width 0.1)
				(type default)
			)
			(layer "B.Fab")
		)
		(fp_line
			(start -0.12065 -0.2794)
			(end -0.12065 -0.3048)
			(stroke
				(width 0.1)
				(type default)
			)
			(layer "B.Fab")
		)
		(fp_line
			(start 0.12065 -0.2794)
			(end -0.12065 -0.2794)
			(stroke
				(width 0.1)
				(type default)
			)
			(layer "B.Fab")
		)
		(fp_line
			(start -0.67945 -0.3048)
			(end -0.67945 0.3048)
			(stroke
				(width 0.1)
				(type default)
			)
			(layer "B.Fab")
		)
		(fp_line
			(start -0.12065 -0.3048)
			(end -0.67945 -0.3048)
			(stroke
				(width 0.1)
				(type default)
			)
			(layer "B.Fab")
		)
		(fp_line
			(start 0.12065 -0.305054)
			(end 0.12065 -0.2794)
			(stroke
				(width 0.1)
				(type default)
			)
			(layer "B.Fab")
		)
		(fp_line
			(start 0.67945 -0.305054)
			(end 0.12065 -0.305054)
			(stroke
				(width 0.1)
				(type default)
			)
			(layer "B.Fab")
		)
		(pad "1" smd circle
			(at 0.40005 0 90)
			(size 0 0)
			(layers "B.Cu" "B.Mask" "B.Paste")
			(net "PVDD18_S5_P0")
		)
		(pad "2" smd circle
			(at -0.40005 0 90)
			(size 0 0)
			(layers "B.Cu" "B.Mask" "B.Paste")
			(net "FM_BOARD_SKU_ID1")
		)
	)
)
